# T6G (Grand Teton) — schematic netlist excerpt (pin names and nets, part order shuffled) for the footprints in the layout excerpt that follows; sources: Cadence DE-HDL packaged netlist, KiCad conversion of 04192023_DAF0TMB3IC0_F0TG_MB_C_brd_V02_OCP.brd

Q118  MOSFET_NCH_DUAL  PJT138K IC  pkg SOT363XD  page 140
  S1  = GND
  G1  = P12V_OCP_EN_2_R
  D2  = P12V_OCP_UV_2_R
  S2  = GND
  G2  = P12V_OCP_2_EN_G
  D1  = P12V_OCP_2_EN_G

TP2  TP  NA  pkg TP  page 27 : TP = VSENSE_VSS_SENSE_B_P0
R996  Q_RES  4.7K 5% CHIP  pkg 0402LF  page 84 : A = P1V8_AUX ; B = SCM_IRQ_1V8_N

(kicad_pcb
	(version 20260206)
	(generator "pcbnew")
	(generator_version "10.0")
	(general
		(thickness 1.6)
		(legacy_teardrops no)
	)
	(paper "A4")
	(title_block
		(title "04192023_DAF0TMB3IC0_F0TG_MB_C_brd_V02_OCP.brd")
		(comment 1 "Grand Teton / footprints 3189-3191 of 8354")
	)
	(layers
		(0 "F.Cu" signal "TOP")
		(4 "In1.Cu" signal "GND")
		(6 "In2.Cu" signal "IN1")
		(8 "In3.Cu" signal "GND1")
		(10 "In4.Cu" signal "IN2")
		(12 "In5.Cu" signal "GND2")
		(14 "In6.Cu" signal "IN3")
		(16 "In7.Cu" signal "GND3")
		(18 "In8.Cu" signal "VCC")
		(20 "In9.Cu" signal "VCC1")
		(22 "In10.Cu" signal "GND4")
		(24 "In11.Cu" signal "IN4")
		(26 "In12.Cu" signal "GND5")
		(28 "In13.Cu" signal "IN5")
		(30 "In14.Cu" signal "GND6")
		(32 "In15.Cu" signal "IN6")
		(34 "In16.Cu" signal "GND7")
		(2 "B.Cu" signal "BOTTOM")
		(9 "F.Adhes" user "F.Adhesive")
		(11 "B.Adhes" user "B.Adhesive")
		(13 "F.Paste" user "Package Geometry/Pastemask Top")
		(15 "B.Paste" user "Package Geometry/Pastemask Bottom")
		(5 "F.SilkS" user "Ref Des/Silkscreen Top")
		(7 "B.SilkS" user "Ref Des/Silkscreen Bottom")
		(1 "F.Mask" user "Board Geometry/Soldermask Top")
		(3 "B.Mask" user "Board Geometry/Soldermask Bottom")
		(17 "Dwgs.User" user "User.Drawings")
		(19 "Cmts.User" user "User.Comments")
		(21 "Eco1.User" user "User.Eco1")
		(23 "Eco2.User" user "User.Eco2")
		(25 "Edge.Cuts" user "Board Geometry/Outline")
		(27 "Margin" user)
		(31 "F.CrtYd" user "Package Geometry/Place Bound Top")
		(29 "B.CrtYd" user "Package Geometry/Place Bound Bottom")
		(35 "F.Fab" user "Ref Des/Assembly Top")
		(33 "B.Fab" user "Ref Des/Assembly Bottom")
	)
	(footprint ""
		(layer "F.Cu")
		(at 148.494242 -110.731046)
		(property "Reference" "R996"
			(at 0 0 0)
			(layer "F.SilkS")
			(hide yes)
			(effects
				(font
					(size 1.27 1.27)
				)
			)
		)
		(property "Value" ""
			(at 0 0 0)
			(layer "F.Fab")
			(effects
				(font
					(size 1.27 1.27)
				)
			)
		)
		(duplicate_pad_numbers_are_jumpers no)
		(fp_line
			(start -0.7874 -0.4064)
			(end 0.7874 -0.4064)
			(stroke
				(width 0.1524)
				(type default)
			)
			(layer "F.SilkS")
		)
		(fp_line
			(start -0.7874 0.4064)
			(end -0.7874 -0.4064)
			(stroke
				(width 0.1524)
				(type default)
			)
			(layer "F.SilkS")
		)
		(fp_line
			(start 0.7874 -0.4064)
			(end 0.7874 0.4064)
			(stroke
				(width 0.1524)
				(type default)
			)
			(layer "F.SilkS")
		)
		(fp_line
			(start 0.7874 0.4064)
			(end -0.7874 0.4064)
			(stroke
				(width 0.1524)
				(type default)
			)
			(layer "F.SilkS")
		)
		(fp_line
			(start -0.67945 -0.305054)
			(end -0.12065 -0.305054)
			(stroke
				(width 0.1)
				(type default)
			)
			(layer "F.Fab")
		)
		(fp_line
			(start -0.67945 0.3048)
			(end -0.67945 -0.305054)
			(stroke
				(width 0.1)
				(type default)
			)
			(layer "F.Fab")
		)
		(fp_line
			(start -0.12065 -0.305054)
			(end -0.12065 -0.2794)
			(stroke
				(width 0.1)
				(type default)
			)
			(layer "F.Fab")
		)
		(fp_line
			(start -0.12065 -0.2794)
			(end 0.12065 -0.2794)
			(stroke
				(width 0.1)
				(type default)
			)
			(layer "F.Fab")
		)
		(fp_line
			(start -0.12065 0.2794)
			(end -0.12065 0.3048)
			(stroke
				(width 0.1)
				(type default)
			)
			(layer "F.Fab")
		)
		(fp_line
			(start -0.12065 0.3048)
			(end -0.67945 0.3048)
			(stroke
				(width 0.1)
				(type default)
			)
			(layer "F.Fab")
		)
		(fp_line
			(start 0.120396 0.2794)
			(end -0.12065 0.2794)
			(stroke
				(width 0.1)
				(type default)
			)
			(layer "F.Fab")
		)
		(fp_line
			(start 0.120396 0.3048)
			(end 0.120396 0.2794)
			(stroke
				(width 0.1)
				(type default)
			)
			(layer "F.Fab")
		)
		(fp_line
			(start 0.12065 -0.3048)
			(end 0.67945 -0.3048)
			(stroke
				(width 0.1)
				(type default)
			)
			(layer "F.Fab")
		)
		(fp_line
			(start 0.12065 -0.2794)
			(end 0.12065 -0.3048)
			(stroke
				(width 0.1)
				(type default)
			)
			(layer "F.Fab")
		)
		(fp_line
			(start 0.67945 -0.3048)
			(end 0.67945 0.3048)
			(stroke
				(width 0.1)
				(type default)
			)
			(layer "F.Fab")
		)
		(fp_line
			(start 0.67945 0.3048)
			(end 0.120396 0.3048)
			(stroke
				(width 0.1)
				(type default)
			)
			(layer "F.Fab")
		)
		(pad "1" smd circle
			(at -0.40005 0)
			(size 0 0)
			(layers "F.Cu" "F.Mask" "F.Paste")
			(net "P1V8_AUX")
		)
		(pad "2" smd circle
			(at 0.40005 0)
			(size 0 0)
			(layers "F.Cu" "F.Mask" "F.Paste")
			(net "SCM_IRQ_1V8_N")
		)
	)
	(footprint ""
		(layer "F.Cu")
		(at 266.862306 -333.031846)
		(property "Reference" "TP2"
			(at -5.423916 0.05207 0)
			(unlocked yes)
			(layer "F.SilkS")
			(effects
				(font
					(size 0.7874 0.5842)
					(thickness 0.1524)
				)
				(justify left)
			)
		)
		(property "Value" ""
			(at 0 0 0)
			(layer "F.Fab")
			(effects
				(font
					(size 1.27 1.27)
				)
			)
		)
		(duplicate_pad_numbers_are_jumpers no)
		(pad "1" smd circle
			(at 0 0)
			(size 0.762 0.762)
			(layers "F.Cu" "F.Mask" "F.Paste")
			(net "VSENSE_VSS_SENSE_B_P0")
		)
	)
	(footprint ""
		(layer "F.Cu")
		(at 62.47257 -37.307266 180)
		(property "Reference" "Q118"
			(at 1.09982 -1.964944 0)
			(unlocked yes)
			(layer "F.SilkS")
			(effects
				(font
					(size 0.7874 0.5842)
					(thickness 0.1524)
				)
				(justify left)
			)
		)
		(property "Value" ""
			(at 0 0 180)
			(layer "F.Fab")
			(effects
				(font
					(size 1.27 1.27)
				)
			)
		)
		(duplicate_pad_numbers_are_jumpers no)
		(fp_line
			(start 1.332738 1.100074)
			(end -1.332738 1.100074)
			(stroke
				(width 0.1524)
				(type default)
			)
			(layer "F.SilkS")
		)
		(fp_line
			(start 1.332738 -1.100074)
			(end 1.332738 1.100074)
			(stroke
				(width 0.1524)
				(type default)
			)
			(layer "F.SilkS")
		)
		(fp_line
			(start 0.4826 -1.100074)
			(end 1.332738 -1.100074)
			(stroke
				(width 0.1524)
				(type default)
			)
			(layer "F.SilkS")
		)
		(fp_line
			(start 0 -0.541274)
			(end 0.4826 -1.100074)
			(stroke
				(width 0.1524)
				(type default)
			)
			(layer "F.SilkS")
		)
		(fp_line
			(start -0.4826 -1.100074)
			(end 0 -0.541274)
			(stroke
				(width 0.1524)
				(type default)
			)
			(layer "F.SilkS")
		)
		(fp_line
			(start -1.332738 1.100074)
			(end -1.332738 -1.100074)
			(stroke
				(width 0.1524)
				(type default)
			)
			(layer "F.SilkS")
		)
		(fp_line
			(start -1.332738 -1.100074)
			(end -0.4826 -1.100074)
			(stroke
				(width 0.1524)
				(type default)
			)
			(layer "F.SilkS")
		)
		(fp_poly
			(pts
				(xy -1.945132 -0.676402) (xy -2.647188 -0.325374) (xy -2.647188 -1.02743)
			)
			(stroke
				(width 0)
				(type default)
			)
			(fill yes)
			(layer "F.SilkS")
		)
		(fp_line
			(start 0.674878 1.100074)
			(end -0.674878 1.100074)
			(stroke
				(width 0.1)
				(type default)
			)
			(layer "F.Fab")
		)
		(fp_line
			(start 0.674878 -1.100074)
			(end 0.674878 1.100074)
			(stroke
				(width 0.1)
				(type default)
			)
			(layer "F.Fab")
		)
		(fp_line
			(start -0.674878 1.100074)
			(end -0.674878 -1.100074)
			(stroke
				(width 0.1)
				(type default)
			)
			(layer "F.Fab")
		)
		(fp_line
			(start -0.674878 -1.100074)
			(end 0.674878 -1.100074)
			(stroke
				(width 0.1)
				(type default)
			)
			(layer "F.Fab")
		)
		(fp_poly
			(pts
				(xy -2.2352 -0.298958) (xy -2.2352 -1.001014) (xy -1.533144 -0.649986)
			)
			(stroke
				(width 0)
				(type default)
			)
			(fill yes)
			(layer "F.Fab")
		)
		(pad "1" smd rect
			(at -0.94996 -0.649986 270)
			(size 0.4318 0.508)
			(layers "F.Cu" "F.Mask" "F.Paste")
			(net "GND")
		)
		(pad "2" smd rect
			(at -0.94996 0 270)
			(size 0.4318 0.508)
			(layers "F.Cu" "F.Mask" "F.Paste")
			(net "P12V_OCP_EN_2_R")
		)
		(pad "3" smd rect
			(at -0.94996 0.649986 270)
			(size 0.4318 0.508)
			(layers "F.Cu" "F.Mask" "F.Paste")
			(net "P12V_OCP_UV_2_R")
		)
		(pad "4" smd rect
			(at 0.94996 0.649986 270)
			(size 0.4318 0.508)
			(layers "F.Cu" "F.Mask" "F.Paste")
			(net "GND")
		)
		(pad "5" smd rect
			(at 0.94996 0 270)
			(size 0.4318 0.508)
			(layers "F.Cu" "F.Mask" "F.Paste")
			(net "P12V_OCP_2_EN_G")
		)
		(pad "6" smd rect
			(at 0.94996 -0.649986 270)
			(size 0.4318 0.508)
			(layers "F.Cu" "F.Mask" "F.Paste")
			(net "P12V_OCP_2_EN_G")
		)
	)
)
